FILE_TYPE = CONNECTIVITY;
{Allegro Design Entry HDL 16.6-p007 (v16-6-112F) 10/10/2012}
"PAGE_NUMBER" = 197;
0"NC";
1"P12V_STBY\g";
2"GND\g";
3"P12V_NVDIMM_DEF\g";
4"P12V_STBY\g";
5"GND\g";
6"P12V_NVDIMM_KLM\g";
7"GND\g";
8"P12V_STBY\g";
9"GND\g";
10"P12V_NVDIMM_GHJ\g";
11"GND\g";
12"P12V_NVDIMM_GHJ\g";
13"GND\g";
14"GND\g";
15"P12V_NVDIMM_KLM\g";
16"GND\g";
17"P12V_NVDIMM_GHJ\g";
18"GND\g";
19"P12V_NVDIMM_GHJ\g";
20"GND\g";
21"GND\g";
22"P12V_NVDIMM_KLM\g";
23"GND\g";
24"P12V_NVDIMM_KLM\g";
25"GND\g";
26"P12V_NVDIMM_DEF\g";
27"GND\g";
28"P12V_NVDIMM_ABC\g";
29"GND\g";
30"P12V_NVDIMM_ABC\g";
31"P12V_NVDIMM_DEF\g";
32"GND\g";
33"P12V_NVDIMM_DEF\g";
34"P12V_STBY\g";
35"P12V_NVDIMM_ABC\g";
36"P12V_NVDIMM_ABC\g";
37"PWRGD_PVDDQ_ABC_N";
38"P12V_NVDIMM_ABC_D";
39"VR_PVDDQ_ABC_VINSEN";
40"VR_PVDDQ_ABC_AIINSEN";
41"VR_PVDDQ_GHJ_VINSEN";
42"VR_PVDDQ_GHJ_AIINSEN";
43"P12V_NVDIMM_DEF_D";
44"P12V_NVDIMM_GHJ_D";
45"PWRGD_PVDDQ_ABC";
46"PWRGD_PVDDQ_GHJ";
47"PWRGD_PVDDQ_GHJ_N";
48"PWRGD_PVDDQ_KLM_N";
49"PWRGD_PVDDQ_DEF_N";
50"PWRGD_PVDDQ_KLM";
51"VR_PVDDQ_DEF_VINSEN";
52"VR_PVDDQ_DEF_AIINSEN";
53"PWRGD_PVDDQ_DEF";
54"VR_PVDDQ_KLM_AIINSEN";
55"VR_PVDDQ_KLM_VINSEN";
56"P12V_NVDIMM_KLM_D";
%"CAP"
"1","(-4275,1450)","1","mstr_discrete","I1";
;
TOLERANCE"5%"
VOLTAGE"50V"
VALUE"47.0PF"
LOCATION"C12W2"
PACK_TYPE"0402LF"
PART_NUMBER"A36095-025"
MATERIAL"COG"
ROOM"BMC_VOLT_MONITOR"
SEC"1"
SEC_TYPE"0402LF"
CDS_LIB"mstr_discrete"
BOM_COST"SM_HM"
CDS_LOCATION"C12W2"
CDS_SEC"1";
"A"
$PN"1"52;
"B"
$PN"2"51;
%"665KR5B-1-GP"
"1","(-4475,4125)","0","w_hdl","I101";
;
CDS_SEC"1"
$SEC"1"
CDS_LOCATION"R12W1"
CONFIG"064.1003F.M001"
NEW_VALUE"100K OHM"
LOCATION"R12W1"
PACK_SIZE"AT0805"
RATED"1/8W"
TOLERANCE"0.1%"
CDS_LMAN_SYM_OUTLINE"-50,75,50,-75"
CDS_LIB"w_hdl"
PART_NUMBER"064.6653F.M001"
PACK_TYPE"SMD-RG3"
ATTRIBUTE"665K OHM"
VALUE"665KR5B-1-GP";
"2"
$PN"2"40;
"1"
$PN"1"34;
%"665KR2B-GP"
"1","(-4250,1700)","1","w_hdl","I109";
;
CDS_SEC"1"
CDS_LOCATION"R12W10"
TOLERANCE"0.1%"
PACK_SIZE"0402"
RATED"1/16W"
VALUE"665KR2B-GP"
ATTRIBUTE"665KOHM"
POP"NOPOP"
LOCATION"R12W10"
CDS_LMAN_SYM_OUTLINE"-50,75,50,-75"
CDS_LIB"w_hdl"
PART_NUMBER"064.6653D.06DD"
SEC_TYPE"SMD-RG2"
SEC"1"
PACK_TYPE"SMD-RG2";
"2"
$PN"2"51;
"1"
$PN"1"52;
%"665KR2B-GP"
"1","(-1700,1700)","1","w_hdl","I110";
;
CDS_SEC"1"
CDS_LOCATION"R12W20"
VALUE"665KR2B-GP"
ATTRIBUTE"665KOHM"
LOCATION"R12W20"
POP"NOPOP"
RATED"1/16W"
TOLERANCE"0.1%"
PACK_SIZE"0402"
CDS_LMAN_SYM_OUTLINE"-50,75,50,-75"
CDS_LIB"w_hdl"
PART_NUMBER"064.6653D.06DD"
SEC_TYPE"SMD-RG2"
SEC"1"
PACK_TYPE"SMD-RG2";
"2"
$PN"2"55;
"1"
$PN"1"54;
%"665KR2B-GP"
"1","(-4250,3800)","1","w_hdl","I111";
;
CDS_SEC"1"
CDS_LOCATION"R12W5"
TOLERANCE"0.1%"
PACK_SIZE"0402"
RATED"1/16W"
ATTRIBUTE"665KOHM"
VALUE"665KR2B-GP"
LOCATION"R12W5"
POP"NOPOP"
PACK_TYPE"SMD-RG2"
SEC"1"
SEC_TYPE"SMD-RG2"
PART_NUMBER"064.6653D.06DD"
CDS_LIB"w_hdl"
CDS_LMAN_SYM_OUTLINE"-50,75,50,-75";
"2"
$PN"2"39;
"1"
$PN"1"40;
%"665KR2B-GP"
"1","(-1700,3800)","1","w_hdl","I112";
;
CDS_SEC"1"
CDS_LOCATION"R12W15"
PACK_SIZE"0402"
VALUE"665KR2B-GP"
ATTRIBUTE"665KOHM"
LOCATION"R12W15"
POP"NOPOP"
RATED"1/16W"
TOLERANCE"0.1%"
PACK_TYPE"SMD-RG2"
SEC"1"
SEC_TYPE"SMD-RG2"
PART_NUMBER"064.6653D.06DD"
CDS_LIB"w_hdl"
CDS_LMAN_SYM_OUTLINE"-50,75,50,-75";
"2"
$PN"2"41;
"1"
$PN"1"42;
%"4D02R2F-GP"
"1","(-4250,2450)","1","w_hdl","I113";
;
CDS_SEC"1"
CDS_LOCATION"R12W8"
PACK_SIZE"0402"
ATTRIBUTE"4.02OHM"
TOLERANCE"1%"
RATED"1/16W"
VALUE"4D02R2F-GP"
LOCATION"R12W8"
PART_NUMBER"64.4R025.6DL"
CDS_LIB"w_hdl"
CDS_LMAN_SYM_OUTLINE"-50,75,50,-75"
SEC_TYPE"SMD-RG2"
SEC"1"
PACK_TYPE"SMD-RG2";
"2"
$PN"2"43;
"1"
$PN"1"1;
%"4D02R2F-GP"
"1","(-1700,2450)","1","w_hdl","I114";
;
CDS_SEC"1"
CDS_LOCATION"R12W18"
LOCATION"R12W18"
PACK_SIZE"0402"
TOLERANCE"1%"
ATTRIBUTE"4.02OHM"
RATED"1/16W"
VALUE"4D02R2F-GP"
PACK_TYPE"SMD-RG2"
SEC"1"
SEC_TYPE"SMD-RG2"
CDS_LMAN_SYM_OUTLINE"-50,75,50,-75"
CDS_LIB"w_hdl"
PART_NUMBER"64.4R025.6DL";
"2"
$PN"2"56;
"1"
$PN"1"4;
%"4D02R2F-GP"
"1","(-4250,4550)","1","w_hdl","I115";
;
CDS_SEC"1"
CDS_LOCATION"R12W3"
ATTRIBUTE"4.02OHM"
RATED"1/16W"
LOCATION"R12W3"
VALUE"4D02R2F-GP"
PACK_SIZE"0402"
TOLERANCE"1%"
PART_NUMBER"64.4R025.6DL"
CDS_LIB"w_hdl"
CDS_LMAN_SYM_OUTLINE"-50,75,50,-75"
SEC_TYPE"SMD-RG2"
SEC"1"
PACK_TYPE"SMD-RG2";
"2"
$PN"2"38;
"1"
$PN"1"34;
%"4D02R2F-GP"
"1","(-1700,4550)","1","w_hdl","I116";
;
CDS_SEC"1"
CDS_LOCATION"R12W13"
PACK_SIZE"0402"
TOLERANCE"1%"
VALUE"4D02R2F-GP"
LOCATION"R12W13"
RATED"1/16W"
ATTRIBUTE"4.02OHM"
PART_NUMBER"64.4R025.6DL"
CDS_LIB"w_hdl"
CDS_LMAN_SYM_OUTLINE"-50,75,50,-75"
SEC_TYPE"SMD-RG2"
SEC"1"
PACK_TYPE"SMD-RG2";
"2"
$PN"2"44;
"1"
$PN"1"8;
%"665KR5B-1-GP"
"1","(-4025,4125)","0","w_hdl","I117";
;
CDS_SEC"1"
$SEC"1"
CDS_LOCATION"R12W2"
NEW_VALUE"100K OHM"
LOCATION"R12W2"
TOLERANCE"0.1%"
RATED"1/8W"
PACK_SIZE"AT0805"
CONFIG"064.1003F.M001"
VALUE"665KR5B-1-GP"
ATTRIBUTE"665K OHM"
PACK_TYPE"SMD-RG3"
PART_NUMBER"064.6653F.M001"
CDS_LIB"w_hdl"
CDS_LMAN_SYM_OUTLINE"-50,75,50,-75";
"2"
$PN"2"39;
"1"
$PN"1"38;
%"665KR5B-1-GP"
"1","(-1925,4125)","0","w_hdl","I118";
;
CDS_SEC"1"
$SEC"1"
CDS_LOCATION"R12W11"
PACK_SIZE"AT0805"
RATED"1/8W"
TOLERANCE"0.1%"
LOCATION"R12W11"
NEW_VALUE"100K OHM"
CONFIG"064.1003F.M001"
CDS_LMAN_SYM_OUTLINE"-50,75,50,-75"
CDS_LIB"w_hdl"
PART_NUMBER"064.6653F.M001"
PACK_TYPE"SMD-RG3"
ATTRIBUTE"665K OHM"
VALUE"665KR5B-1-GP";
"2"
$PN"2"42;
"1"
$PN"1"8;
%"665KR5B-1-GP"
"1","(-1475,4125)","0","w_hdl","I119";
;
CDS_SEC"1"
$SEC"1"
CDS_LOCATION"R12W12"
LOCATION"R12W12"
TOLERANCE"0.1%"
RATED"1/8W"
CONFIG"064.1003F.M001"
NEW_VALUE"100K OHM"
PACK_SIZE"AT0805"
VALUE"665KR5B-1-GP"
ATTRIBUTE"665K OHM"
PACK_TYPE"SMD-RG3"
PART_NUMBER"064.6653F.M001"
CDS_LIB"w_hdl"
CDS_LMAN_SYM_OUTLINE"-50,75,50,-75";
"2"
$PN"2"41;
"1"
$PN"1"44;
%"665KR5B-1-GP"
"1","(-4475,2025)","0","w_hdl","I120";
;
CDS_SEC"1"
$SEC"1"
CDS_LOCATION"R12W6"
NEW_VALUE"100K OHM"
CONFIG"064.1003F.M001"
TOLERANCE"0.1%"
RATED"1/8W"
PACK_SIZE"AT0805"
LOCATION"R12W6"
VALUE"665KR5B-1-GP"
ATTRIBUTE"665K OHM"
PACK_TYPE"SMD-RG3"
PART_NUMBER"064.6653F.M001"
CDS_LIB"w_hdl"
CDS_LMAN_SYM_OUTLINE"-50,75,50,-75";
"2"
$PN"2"52;
"1"
$PN"1"1;
%"665KR5B-1-GP"
"1","(-4025,2025)","0","w_hdl","I121";
;
CDS_SEC"1"
$SEC"1"
CDS_LOCATION"R12W7"
PACK_SIZE"AT0805"
CONFIG"064.1003F.M001"
NEW_VALUE"100K OHM"
LOCATION"R12W7"
TOLERANCE"0.1%"
RATED"1/8W"
CDS_LMAN_SYM_OUTLINE"-50,75,50,-75"
CDS_LIB"w_hdl"
PART_NUMBER"064.6653F.M001"
PACK_TYPE"SMD-RG3"
ATTRIBUTE"665K OHM"
VALUE"665KR5B-1-GP";
"2"
$PN"2"51;
"1"
$PN"1"43;
%"665KR5B-1-GP"
"1","(-1925,2025)","0","w_hdl","I122";
;
CDS_SEC"1"
$SEC"1"
CDS_LOCATION"R12W16"
CONFIG"064.1003F.M001"
NEW_VALUE"100K OHM"
LOCATION"R12W16"
TOLERANCE"0.1%"
PACK_SIZE"AT0805"
RATED"1/8W"
CDS_LMAN_SYM_OUTLINE"-50,75,50,-75"
CDS_LIB"w_hdl"
PART_NUMBER"064.6653F.M001"
PACK_TYPE"SMD-RG3"
ATTRIBUTE"665K OHM"
VALUE"665KR5B-1-GP";
"2"
$PN"2"54;
"1"
$PN"1"4;
%"665KR5B-1-GP"
"1","(-1475,2025)","0","w_hdl","I123";
;
CDS_SEC"1"
$SEC"1"
CDS_LOCATION"R12W17"
CONFIG"064.1003F.M001"
NEW_VALUE"100K OHM"
LOCATION"R12W17"
TOLERANCE"0.1%"
RATED"1/8W"
PACK_SIZE"AT0805"
VALUE"665KR5B-1-GP"
ATTRIBUTE"665K OHM"
PACK_TYPE"SMD-RG3"
PART_NUMBER"064.6653F.M001"
CDS_LIB"w_hdl"
CDS_LMAN_SYM_OUTLINE"-50,75,50,-75";
"2"
$PN"2"55;
"1"
$PN"1"56;
%"RES"
"1","(-4275,4800)","0","mstr_discrete","I14";
;
WATTAGE"1W"
TOLERANCE"1%"
PACK_TYPE"1206"
PART_NUMBER"G52199-004"
LOCATION"R4F2"
CONFIG"064.R0045.0711"
NEW_VALUE"0.004 OHM"
MATERIAL"CHIP"
VALUE"0.002"
ROOM"PVDDQ_ABC_PWR_VR"
CDS_LOCATION"R4F2"
SEC"1"
CDS_LIB"mstr_discrete"
BOM_COST"PVDDQ_ABC_VR"
SEC_TYPE"1206"
CDS_SEC"1";
"B"
$PN"2"35;
"A"
$PN"1"34;
%"CAP"
"1","(-1725,1450)","1","mstr_discrete","I18";
;
LOCATION"C12W4"
TOLERANCE"5%"
VOLTAGE"50V"
VALUE"47.0PF"
PACK_TYPE"0402LF"
PART_NUMBER"A36095-025"
MATERIAL"COG"
BOM_COST"SM_HM"
CDS_LIB"mstr_discrete"
SEC_TYPE"0402LF"
SEC"1"
ROOM"BMC_VOLT_MONITOR"
CDS_LOCATION"C12W4"
CDS_SEC"1";
"A"
$PN"1"54;
"B"
$PN"2"55;
%"BSL308C-H6327-GP"
"1","(-3250,2000)","0","w_hdl","I19";
;
VALUE"BSL308C-H6327-GP"
LOCATION"Q12W2"
PACK_TYPE"DISCRET-GB1"
SEC"1"
SEC_TYPE"DISCRET-GB1"
CDS_LMAN_SYM_OUTLINE"-125,250,125,-250"
CDS_LIB"w_hdl"
PART_NUMBER"075.00308.007C"
CDS_LOCATION"Q12W2"
CDS_SEC"1";
"DRAIN#4"
$PN"4"43;
"GATE#3"
$PN"3"49;
"SOURCE#5"
$PN"5"2;
"DRAIN#6"
$PN"6"49;
"SOURCE#2"
$PN"2"3;
"GATE#1"
$PN"1"53;
%"P12V_STBY"
"1","(-4525,2850)","0","mstr_symbols","I2";
;
HDL_POWER"P12V_STBY"
BODY_TYPE"PLUMBING"
VOLTAGE"12.0V"
SIZE"1B"
CDS_LIB"mstr_symbols";
"G\NAC"1;
%"GND"
"1","(-2925,1900)","0","mstr_symbols","I20";
;
HDL_POWER"GND"
BODY_TYPE"PLUMBING"
CDS_LIB"mstr_symbols"
SIZE"1B"
VOLTAGE"0.0V";
"A\NAC"2;
%"RES"
"2","(-2725,2400)","0","mstr_discrete","I21";
;
VALUE"100.0K"
TOLERANCE"1%"
LOCATION"R12W9"
WATTAGE"1/10W"
MATERIAL"CHIP"
PACK_TYPE"0603"
PART_NUMBER"G22026-050"
SEC_TYPE"0603"
SEC"1"
BOM_COST"PROC_SOCKET"
ROOM"CPU0"
CDS_LIB"mstr_discrete"
CDS_LOCATION"R12W9"
CDS_SEC"1";
"A"
$PN"1"3;
"B"
$PN"2"49;
%"P12V_NVDIMM_DEF"
"1","(-2675,2850)","0","mstr_symbols","I23";
;
HDL_POWER"P12V_NVDIMM_DEF"
BODY_TYPE"PLUMBING"
VOLTAGE"12.0"
CDS_LIB"mstr_symbols";
"G\NAC"3;
%"RES"
"1","(-1725,2700)","0","mstr_discrete","I29";
;
TOLERANCE"1%"
WATTAGE"1W"
MATERIAL"CHIP"
PACK_TYPE"1206"
LOCATION"R9M4"
PART_NUMBER"G52199-004"
NEW_VALUE"0.004 OHM"
CONFIG"064.R0045.0711"
VALUE"0.002"
ROOM"PVDDQ_ABC_PWR_VR"
SEC"1"
CDS_LIB"mstr_discrete"
BOM_COST"PVDDQ_ABC_VR"
SEC_TYPE"1206"
CDS_LOCATION"R9M4"
CDS_SEC"1";
"B"
$PN"2"6;
"A"
$PN"1"4;
%"P12V_STBY"
"1","(-1975,2850)","0","mstr_symbols","I30";
;
HDL_POWER"P12V_STBY"
BODY_TYPE"PLUMBING"
CDS_LIB"mstr_symbols"
SIZE"1B"
VOLTAGE"12.0V";
"G\NAC"4;
%"BSL308C-H6327-GP"
"1","(-700,2000)","0","w_hdl","I35";
;
LOCATION"Q12W4"
VALUE"BSL308C-H6327-GP"
PART_NUMBER"075.00308.007C"
CDS_LIB"w_hdl"
CDS_LMAN_SYM_OUTLINE"-125,250,125,-250"
SEC_TYPE"DISCRET-GB1"
SEC"1"
PACK_TYPE"DISCRET-GB1"
CDS_LOCATION"Q12W4"
CDS_SEC"1";
"DRAIN#4"
$PN"4"56;
"GATE#3"
$PN"3"48;
"SOURCE#5"
$PN"5"5;
"DRAIN#6"
$PN"6"48;
"SOURCE#2"
$PN"2"6;
"GATE#1"
$PN"1"50;
%"GND"
"1","(-375,1900)","0","mstr_symbols","I36";
;
HDL_POWER"GND"
BODY_TYPE"PLUMBING"
VOLTAGE"0.0V"
SIZE"1B"
CDS_LIB"mstr_symbols";
"A\NAC"5;
%"RES"
"2","(-175,2400)","0","mstr_discrete","I37";
;
TOLERANCE"1%"
LOCATION"R12W19"
PACK_TYPE"0603"
PART_NUMBER"G22026-050"
MATERIAL"CHIP"
WATTAGE"1/10W"
VALUE"100.0K"
CDS_LIB"mstr_discrete"
ROOM"CPU0"
BOM_COST"PROC_SOCKET"
SEC"1"
SEC_TYPE"0603"
CDS_LOCATION"R12W19"
CDS_SEC"1";
"A"
$PN"1"6;
"B"
$PN"2"48;
%"P12V_NVDIMM_KLM"
"1","(-125,2850)","0","mstr_symbols","I38";
;
HDL_POWER"P12V_NVDIMM_KLM"
BODY_TYPE"PLUMBING"
CDS_LIB"mstr_symbols"
VOLTAGE"12.0";
"G\NAC"6;
%"CAP"
"1","(-1725,3550)","1","mstr_discrete","I42";
;
VALUE"47.0PF"
VOLTAGE"50V"
LOCATION"C12W3"
TOLERANCE"5%"
PACK_TYPE"0402LF"
PART_NUMBER"A36095-025"
MATERIAL"COG"
ROOM"BMC_VOLT_MONITOR"
SEC"1"
SEC_TYPE"0402LF"
CDS_LIB"mstr_discrete"
BOM_COST"SM_HM"
CDS_LOCATION"C12W3"
CDS_SEC"1";
"A"
$PN"1"42;
"B"
$PN"2"41;
%"BSL308C-H6327-GP"
"1","(-3250,4100)","0","w_hdl","I43";
;
LOCATION"Q12W1"
VALUE"BSL308C-H6327-GP"
PART_NUMBER"075.00308.007C"
CDS_LIB"w_hdl"
CDS_LMAN_SYM_OUTLINE"-125,250,125,-250"
SEC_TYPE"DISCRET-GB1"
SEC"1"
PACK_TYPE"DISCRET-GB1"
CDS_LOCATION"Q12W1"
CDS_SEC"1";
"DRAIN#4"
$PN"4"38;
"GATE#3"
$PN"3"37;
"SOURCE#5"
$PN"5"7;
"DRAIN#6"
$PN"6"37;
"SOURCE#2"
$PN"2"35;
"GATE#1"
$PN"1"45;
%"GND"
"1","(-2925,4000)","0","mstr_symbols","I44";
;
HDL_POWER"GND"
BODY_TYPE"PLUMBING"
VOLTAGE"0.0V"
SIZE"1B"
CDS_LIB"mstr_symbols";
"A\NAC"7;
%"RES"
"2","(-2725,4500)","0","mstr_discrete","I45";
;
PART_NUMBER"G22026-050"
PACK_TYPE"0603"
WATTAGE"1/10W"
TOLERANCE"1%"
MATERIAL"CHIP"
VALUE"100.0K"
LOCATION"R12W4"
CDS_LIB"mstr_discrete"
ROOM"CPU0"
BOM_COST"PROC_SOCKET"
SEC"1"
SEC_TYPE"0603"
CDS_LOCATION"R12W4"
CDS_SEC"1";
"A"
$PN"1"35;
"B"
$PN"2"37;
%"P12V_STBY"
"1","(-1975,4950)","0","mstr_symbols","I49";
;
HDL_POWER"P12V_STBY"
BODY_TYPE"PLUMBING"
VOLTAGE"12.0V"
SIZE"1B"
CDS_LIB"mstr_symbols";
"G\NAC"8;
%"RES"
"1","(-1725,4800)","0","mstr_discrete","I50";
;
TOLERANCE"1%"
WATTAGE"1W"
PACK_TYPE"1206"
LOCATION"R1F3"
MATERIAL"CHIP"
PART_NUMBER"G52199-004"
NEW_VALUE"0.004 OHM"
CONFIG"064.R0045.0711"
VALUE"0.002"
SEC_TYPE"1206"
BOM_COST"PVDDQ_ABC_VR"
CDS_LIB"mstr_discrete"
SEC"1"
ROOM"PVDDQ_ABC_PWR_VR"
CDS_LOCATION"R1F3"
CDS_SEC"1";
"B"
$PN"2"10;
"A"
$PN"1"8;
%"GND"
"1","(-375,4000)","0","mstr_symbols","I52";
;
HDL_POWER"GND"
BODY_TYPE"PLUMBING"
CDS_LIB"mstr_symbols"
SIZE"1B"
VOLTAGE"0.0V";
"A\NAC"9;
%"RES"
"2","(-175,4500)","0","mstr_discrete","I53";
;
VALUE"100.0K"
PACK_TYPE"0603"
LOCATION"R12W14"
WATTAGE"1/10W"
TOLERANCE"1%"
MATERIAL"CHIP"
PART_NUMBER"G22026-050"
SEC_TYPE"0603"
SEC"1"
BOM_COST"PROC_SOCKET"
ROOM"CPU0"
CDS_LIB"mstr_discrete"
CDS_LOCATION"R12W14"
CDS_SEC"1";
"A"
$PN"1"10;
"B"
$PN"2"47;
%"P12V_NVDIMM_GHJ"
"1","(-125,4950)","0","mstr_symbols","I54";
;
HDL_POWER"P12V_NVDIMM_GHJ"
BODY_TYPE"PLUMBING"
VOLTAGE"12.0"
CDS_LIB"mstr_symbols";
"G\NAC"10;
%"GND"
"1","(1325,1100)","0","mstr_symbols","I55";
;
HDL_POWER"GND"
BODY_TYPE"PLUMBING"
CDS_LIB"mstr_symbols"
SIZE"1B"
VOLTAGE"0.0V";
"A\NAC"11;
%"CAP"
"1","(1325,1275)","0","mstr_discrete","I56";
;
PACK_TYPE"0805"
PART_NUMBER"G10601-001"
MATERIAL"X7R"
TOLERANCE"10%"
VALUE"10UF"
LOCATION"C9T8"
VOLTAGE"16V"
ROOM"PVDDQ_GHJ_PWR_VR"
CDS_LOCATION"C9T8"
$SEC"1"
CDS_SEC"1"
CDS_LIB"mstr_discrete";
"A"
$PN"1"12;
"B"
$PN"2"11;
%"P12V_NVDIMM_GHJ"
"1","(1325,1450)","0","mstr_symbols","I57";
;
HDL_POWER"P12V_NVDIMM_GHJ"
BODY_TYPE"PLUMBING"
CDS_LIB"mstr_symbols"
VOLTAGE"12.0";
"G\NAC"12;
%"GND"
"1","(1325,1675)","0","mstr_symbols","I58";
;
HDL_POWER"GND"
BODY_TYPE"PLUMBING"
SIZE"1B"
CDS_LIB"mstr_symbols"
VOLTAGE"0.0V";
"A\NAC"13;
%"GND"
"1","(2175,1075)","0","mstr_symbols","I59";
;
HDL_POWER"GND"
BODY_TYPE"PLUMBING"
SIZE"1B"
CDS_LIB"mstr_symbols"
VOLTAGE"0.0V";
"A\NAC"14;
%"RES"
"1","(-4275,2700)","0","mstr_discrete","I6";
;
LOCATION"R4B12"
PART_NUMBER"G52199-004"
PACK_TYPE"1206"
MATERIAL"CHIP"
WATTAGE"1W"
TOLERANCE"1%"
CONFIG"064.R0045.0711"
NEW_VALUE"0.004 OHM"
CDS_SEC"1"
CDS_LOCATION"R4B12"
ROOM"PVDDQ_ABC_PWR_VR"
SEC"1"
CDS_LIB"mstr_discrete"
BOM_COST"PVDDQ_ABC_VR"
SEC_TYPE"1206"
VALUE"0.002";
"B"
$PN"2"3;
"A"
$PN"1"1;
%"CAP"
"1","(2175,1275)","0","mstr_discrete","I60";
;
PART_NUMBER"G10601-001"
PACK_TYPE"0805"
VALUE"10UF"
TOLERANCE"10%"
VOLTAGE"16V"
MATERIAL"X7R"
LOCATION"C1A4"
ROOM"PVDDQ_KLM_PWR_VR"
CDS_LOCATION"C1A4"
$SEC"1"
CDS_SEC"1"
CDS_LIB"mstr_discrete";
"A"
$PN"1"15;
"B"
$PN"2"14;
%"P12V_NVDIMM_KLM"
"1","(2175,1450)","0","mstr_symbols","I61";
;
HDL_POWER"P12V_NVDIMM_KLM"
BODY_TYPE"PLUMBING"
CDS_LIB"mstr_symbols"
VOLTAGE"12.0";
"G\NAC"15;
%"GND"
"1","(2175,1650)","0","mstr_symbols","I62";
;
HDL_POWER"GND"
BODY_TYPE"PLUMBING"
SIZE"1B"
CDS_LIB"mstr_symbols"
VOLTAGE"0.0V";
"A\NAC"16;
%"CAP"
"1","(1325,1850)","0","mstr_discrete","I63";
;
PART_NUMBER"G10601-001"
PACK_TYPE"0805"
TOLERANCE"10%"
MATERIAL"X7R"
VOLTAGE"16V"
LOCATION"C9U11"
VALUE"10UF"
ROOM"PVDDQ_GHJ_PWR_VR"
CDS_LOCATION"C9U11"
$SEC"1"
CDS_SEC"1"
CDS_LIB"mstr_discrete";
"A"
$PN"1"17;
"B"
$PN"2"13;
%"P12V_NVDIMM_GHJ"
"1","(1325,2025)","0","mstr_symbols","I64";
;
HDL_POWER"P12V_NVDIMM_GHJ"
BODY_TYPE"PLUMBING"
CDS_LIB"mstr_symbols"
VOLTAGE"12.0";
"G\NAC"17;
%"GND"
"1","(1325,2325)","0","mstr_symbols","I65";
;
HDL_POWER"GND"
BODY_TYPE"PLUMBING"
CDS_LIB"mstr_symbols"
SIZE"1B"
VOLTAGE"0.0V";
"A\NAC"18;
%"CAP"
"1","(1325,2500)","0","mstr_discrete","I66";
;
PACK_TYPE"0805"
PART_NUMBER"G10601-001"
MATERIAL"X7R"
VOLTAGE"16V"
VALUE"10UF"
LOCATION"C9U8"
TOLERANCE"10%"
ROOM"PVDDQ_GHJ_PWR_VR"
CDS_LOCATION"C9U8"
$SEC"1"
CDS_SEC"1"
CDS_LIB"mstr_discrete";
"A"
$PN"1"19;
"B"
$PN"2"18;
%"P12V_NVDIMM_GHJ"
"1","(1325,2675)","0","mstr_symbols","I67";
;
HDL_POWER"P12V_NVDIMM_GHJ"
BODY_TYPE"PLUMBING"
CDS_LIB"mstr_symbols"
VOLTAGE"12.0";
"G\NAC"19;
%"GND"
"1","(1325,2975)","0","mstr_symbols","I68";
;
HDL_POWER"GND"
BODY_TYPE"PLUMBING"
CDS_LIB"mstr_symbols"
SIZE"1B"
VOLTAGE"0.0V";
"A\NAC"20;
%"CAP"
"1","(1325,3175)","0","mstr_discrete","I69";
;
PART_NUMBER"G10601-001"
VALUE"10UF"
LOCATION"C6U18"
PACK_TYPE"0805"
MATERIAL"X7R"
VOLTAGE"16V"
TOLERANCE"10%"
ROOM"PVDDQ_ABC_PWR_VR"
CDS_LOCATION"C6U18"
$SEC"1"
CDS_SEC"1"
CDS_LIB"mstr_discrete";
"A"
$PN"1"36;
"B"
$PN"2"20;
%"GND"
"1","(1325,3550)","0","mstr_symbols","I70";
;
HDL_POWER"GND"
BODY_TYPE"PLUMBING"
CDS_LIB"mstr_symbols"
SIZE"1B"
VOLTAGE"0.0V";
"A\NAC"21;
%"CAP"
"1","(1325,3750)","0","mstr_discrete","I71";
;
TOLERANCE"10%"
PART_NUMBER"G10601-001"
PACK_TYPE"0805"
VALUE"10UF"
MATERIAL"X7R"
VOLTAGE"16V"
LOCATION"C6T2"
ROOM"PVDDQ_ABC_PWR_VR"
CDS_LOCATION"C6T2"
$SEC"1"
CDS_SEC"1"
CDS_LIB"mstr_discrete";
"A"
$PN"1"28;
"B"
$PN"2"21;
%"CAP"
"1","(2175,1850)","0","mstr_discrete","I72";
;
MATERIAL"X7R"
TOLERANCE"10%"
PACK_TYPE"0805"
LOCATION"C1B7"
VOLTAGE"16V"
VALUE"10UF"
PART_NUMBER"G10601-001"
ROOM"PVDDQ_KLM_PWR_VR"
CDS_LOCATION"C1B7"
$SEC"1"
CDS_SEC"1"
CDS_LIB"mstr_discrete";
"A"
$PN"1"22;
"B"
$PN"2"16;
%"P12V_NVDIMM_KLM"
"1","(2175,2025)","0","mstr_symbols","I73";
;
HDL_POWER"P12V_NVDIMM_KLM"
BODY_TYPE"PLUMBING"
CDS_LIB"mstr_symbols"
VOLTAGE"12.0";
"G\NAC"22;
%"GND"
"1","(2175,2300)","0","mstr_symbols","I74";
;
HDL_POWER"GND"
BODY_TYPE"PLUMBING"
SIZE"1B"
CDS_LIB"mstr_symbols"
VOLTAGE"0.0V";
"A\NAC"23;
%"CAP"
"1","(2175,2500)","0","mstr_discrete","I75";
;
TOLERANCE"10%"
PACK_TYPE"0805"
PART_NUMBER"G10601-001"
LOCATION"C1A16"
VALUE"10UF"
VOLTAGE"16V"
MATERIAL"X7R"
ROOM"PVDDQ_KLM_PWR_VR"
CDS_LOCATION"C1A16"
$SEC"1"
CDS_SEC"1"
CDS_LIB"mstr_discrete";
"A"
$PN"1"24;
"B"
$PN"2"23;
%"P12V_NVDIMM_KLM"
"1","(2175,2675)","0","mstr_symbols","I76";
;
HDL_POWER"P12V_NVDIMM_KLM"
BODY_TYPE"PLUMBING"
CDS_LIB"mstr_symbols"
VOLTAGE"12.0";
"G\NAC"24;
%"GND"
"1","(2175,2975)","0","mstr_symbols","I77";
;
HDL_POWER"GND"
BODY_TYPE"PLUMBING"
SIZE"1B"
CDS_LIB"mstr_symbols"
VOLTAGE"0.0V";
"A\NAC"25;
%"CAP"
"1","(2175,3175)","0","mstr_discrete","I78";
;
TOLERANCE"10%"
PART_NUMBER"G10601-001"
PACK_TYPE"0805"
VOLTAGE"16V"
VALUE"10UF"
LOCATION"C4B11"
MATERIAL"X7R"
ROOM"PVDDQ_DEF_PWR_VR"
CDS_LOCATION"C4B11"
$SEC"1"
CDS_SEC"1"
CDS_LIB"mstr_discrete";
"A"
$PN"1"26;
"B"
$PN"2"25;
%"P12V_NVDIMM_DEF"
"1","(2175,3350)","0","mstr_symbols","I79";
;
HDL_POWER"P12V_NVDIMM_DEF"
BODY_TYPE"PLUMBING"
CDS_LIB"mstr_symbols"
VOLTAGE"12.0";
"G\NAC"26;
%"CAP"
"1","(-4275,3550)","1","mstr_discrete","I8";
;
TOLERANCE"5%"
PART_NUMBER"A36095-025"
MATERIAL"COG"
PACK_TYPE"0402LF"
VOLTAGE"50V"
VALUE"47.0PF"
LOCATION"C12W1"
BOM_COST"SM_HM"
CDS_LIB"mstr_discrete"
SEC_TYPE"0402LF"
SEC"1"
ROOM"BMC_VOLT_MONITOR"
CDS_LOCATION"C12W1"
CDS_SEC"1";
"A"
$PN"1"40;
"B"
$PN"2"39;
%"GND"
"1","(2175,3550)","0","mstr_symbols","I80";
;
HDL_POWER"GND"
BODY_TYPE"PLUMBING"
SIZE"1B"
CDS_LIB"mstr_symbols"
VOLTAGE"0.0V";
"A\NAC"27;
%"CAP"
"1","(2175,3750)","0","mstr_discrete","I81";
;
MATERIAL"X7R"
VOLTAGE"16V"
TOLERANCE"10%"
PART_NUMBER"G10601-001"
PACK_TYPE"0805"
VALUE"10UF"
LOCATION"C4A4"
ROOM"PVDDQ_DEF_PWR_VR"
CDS_LOCATION"C4A4"
$SEC"1"
CDS_SEC"1"
CDS_LIB"mstr_discrete";
"A"
$PN"1"31;
"B"
$PN"2"27;
%"P12V_NVDIMM_ABC"
"1","(1325,3925)","0","mstr_symbols","I82";
;
HDL_POWER"P12V_NVDIMM_ABC"
BODY_TYPE"PLUMBING"
CDS_LIB"mstr_symbols"
VOLTAGE"12.0";
"G\NAC"28;
%"GND"
"1","(1325,4200)","0","mstr_symbols","I83";
;
HDL_POWER"GND"
BODY_TYPE"PLUMBING"
CDS_LIB"mstr_symbols"
SIZE"1B"
VOLTAGE"0.0V";
"A\NAC"29;
%"CAP"
"1","(1325,4400)","0","mstr_discrete","I84";
;
PART_NUMBER"G10601-001"
MATERIAL"X7R"
LOCATION"C6U10"
VALUE"10UF"
VOLTAGE"16V"
PACK_TYPE"0805"
TOLERANCE"10%"
ROOM"PVDDQ_ABC_PWR_VR"
CDS_LOCATION"C6U10"
$SEC"1"
CDS_SEC"1"
CDS_LIB"mstr_discrete";
"A"
$PN"1"30;
"B"
$PN"2"29;
%"P12V_NVDIMM_ABC"
"1","(1325,4575)","0","mstr_symbols","I85";
;
HDL_POWER"P12V_NVDIMM_ABC"
BODY_TYPE"PLUMBING"
CDS_LIB"mstr_symbols"
VOLTAGE"12.0";
"G\NAC"30;
%"P12V_NVDIMM_DEF"
"1","(2175,3925)","0","mstr_symbols","I86";
;
HDL_POWER"P12V_NVDIMM_DEF"
BODY_TYPE"PLUMBING"
CDS_LIB"mstr_symbols"
VOLTAGE"12.0";
"G\NAC"31;
%"GND"
"1","(2175,4200)","0","mstr_symbols","I87";
;
HDL_POWER"GND"
BODY_TYPE"PLUMBING"
CDS_LIB"mstr_symbols"
SIZE"1B"
VOLTAGE"0.0V";
"A\NAC"32;
%"CAP"
"1","(2175,4400)","0","mstr_discrete","I88";
;
MATERIAL"X7R"
VOLTAGE"16V"
TOLERANCE"10%"
VALUE"10UF"
LOCATION"C4A17"
PART_NUMBER"G10601-001"
PACK_TYPE"0805"
ROOM"PVDDQ_DEF_PWR_VR"
CDS_LOCATION"C4A17"
$SEC"1"
CDS_SEC"1"
CDS_LIB"mstr_discrete";
"A"
$PN"1"33;
"B"
$PN"2"32;
%"P12V_NVDIMM_DEF"
"1","(2175,4575)","0","mstr_symbols","I89";
;
HDL_POWER"P12V_NVDIMM_DEF"
BODY_TYPE"PLUMBING"
CDS_LIB"mstr_symbols"
VOLTAGE"12.0";
"G\NAC"33;
%"P12V_STBY"
"1","(-4525,4950)","0","mstr_symbols","I9";
;
HDL_POWER"P12V_STBY"
BODY_TYPE"PLUMBING"
CDS_LIB"mstr_symbols"
SIZE"1B"
VOLTAGE"12.0V";
"G\NAC"34;
%"P12V_NVDIMM_ABC"
"1","(-2675,4950)","0","mstr_symbols","I90";
;
HDL_POWER"P12V_NVDIMM_ABC"
BODY_TYPE"PLUMBING"
CDS_LIB"mstr_symbols"
VOLTAGE"12.0";
"G\NAC"35;
%"BSL308C-H6327-GP"
"1","(-700,4100)","0","w_hdl","I91";
;
LOCATION"Q12W3"
VALUE"BSL308C-H6327-GP"
PACK_TYPE"DISCRET-GB1"
SEC"1"
SEC_TYPE"DISCRET-GB1"
CDS_LMAN_SYM_OUTLINE"-125,250,125,-250"
CDS_LIB"w_hdl"
PART_NUMBER"075.00308.007C"
CDS_LOCATION"Q12W3"
CDS_SEC"1";
"DRAIN#4"
$PN"4"44;
"GATE#3"
$PN"3"47;
"SOURCE#5"
$PN"5"9;
"DRAIN#6"
$PN"6"47;
"SOURCE#2"
$PN"2"10;
"GATE#1"
$PN"1"46;
%"P12V_NVDIMM_ABC"
"1","(1325,3350)","0","mstr_symbols","I92";
;
HDL_POWER"P12V_NVDIMM_ABC"
BODY_TYPE"PLUMBING"
CDS_LIB"mstr_symbols"
VOLTAGE"12.0";
"G\NAC"36;
END.
